(kicad_pcb
	(version 20260206)
	(generator "pcbnew")
	(generator_version "10.0")
	(general
		(thickness 1.6)
		(legacy_teardrops no)
	)
	(paper "A4")
	(title_block
		(title "04192023_DAF0TMB3IC0_F0TG_MB_C_brd_V02_OCP.brd")
		(comment 1 "Grand Teton / footprints 8225-8231 of 8354")
	)
	(layers
		(0 "F.Cu" signal "TOP")
		(4 "In1.Cu" signal "GND")
		(6 "In2.Cu" signal "IN1")
		(8 "In3.Cu" signal "GND1")
		(10 "In4.Cu" signal "IN2")
		(12 "In5.Cu" signal "GND2")
		(14 "In6.Cu" signal "IN3")
		(16 "In7.Cu" signal "GND3")
		(18 "In8.Cu" signal "VCC")
		(20 "In9.Cu" signal "VCC1")
		(22 "In10.Cu" signal "GND4")
		(24 "In11.Cu" signal "IN4")
		(26 "In12.Cu" signal "GND5")
		(28 "In13.Cu" signal "IN5")
		(30 "In14.Cu" signal "GND6")
		(32 "In15.Cu" signal "IN6")
		(34 "In16.Cu" signal "GND7")
		(2 "B.Cu" signal "BOTTOM")
		(9 "F.Adhes" user "F.Adhesive")
		(11 "B.Adhes" user "B.Adhesive")
		(13 "F.Paste" user "Package Geometry/Pastemask Top")
		(15 "B.Paste" user "Package Geometry/Pastemask Bottom")
		(5 "F.SilkS" user "Ref Des/Silkscreen Top")
		(7 "B.SilkS" user "Ref Des/Silkscreen Bottom")
		(1 "F.Mask" user "Board Geometry/Soldermask Top")
		(3 "B.Mask" user "Board Geometry/Soldermask Bottom")
		(17 "Dwgs.User" user "User.Drawings")
		(19 "Cmts.User" user "User.Comments")
		(21 "Eco1.User" user "User.Eco1")
		(23 "Eco2.User" user "User.Eco2")
		(25 "Edge.Cuts" user "Board Geometry/Outline")
		(27 "Margin" user)
		(31 "F.CrtYd" user "Package Geometry/Place Bound Top")
		(29 "B.CrtYd" user "Package Geometry/Place Bound Bottom")
		(35 "F.Fab" user "Ref Des/Assembly Top")
		(33 "B.Fab" user "Ref Des/Assembly Bottom")
	)
	(footprint ""
		(layer "B.Cu")
		(at 216.027 -339.725 90)
		(property "Reference" "R6751"
			(at 0 0 90)
			(layer "B.SilkS")
			(hide yes)
			(effects
				(font
					(size 1.27 1.27)
				)
				(justify mirror)
			)
		)
		(property "Value" ""
			(at 0 0 90)
			(layer "B.Fab")
			(effects
				(font
					(size 1.27 1.27)
				)
				(justify mirror)
			)
		)
		(duplicate_pad_numbers_are_jumpers no)
		(fp_line
			(start 0.32512 -0.175006)
			(end -0.32512 -0.175006)
			(stroke
				(width 0.1)
				(type default)
			)
			(layer "B.Fab")
		)
		(fp_line
			(start -0.32512 -0.175006)
			(end -0.32512 0.175006)
			(stroke
				(width 0.1)
				(type default)
			)
			(layer "B.Fab")
		)
		(fp_line
			(start 0.32512 0.175006)
			(end 0.32512 -0.175006)
			(stroke
				(width 0.1)
				(type default)
			)
			(layer "B.Fab")
		)
		(fp_line
			(start -0.32512 0.175006)
			(end 0.32512 0.175006)
			(stroke
				(width 0.1)
				(type default)
			)
			(layer "B.Fab")
		)
		(pad "1" smd rect
			(at 0.2667 0 270)
			(size 0.3048 0.381)
			(layers "B.Cu" "B.Mask" "B.Paste")
			(net "P1V8_CPU1_RT_1D")
		)
		(pad "2" smd rect
			(at -0.2667 0 90)
			(size 0.3048 0.381)
			(layers "B.Cu" "B.Mask" "B.Paste")
			(net "SMB_RT_CPU1_P3_R_SCL")
		)
	)
	(footprint ""
		(layer "B.Cu")
		(at 73.65873 -335.06791 90)
		(property "Reference" "PC412_3"
			(at 0 0 90)
			(layer "B.SilkS")
			(hide yes)
			(effects
				(font
					(size 1.27 1.27)
				)
				(justify mirror)
			)
		)
		(property "Value" ""
			(at 0 0 90)
			(layer "B.Fab")
			(effects
				(font
					(size 1.27 1.27)
				)
				(justify mirror)
			)
		)
		(duplicate_pad_numbers_are_jumpers no)
		(fp_line
			(start 1.524 -0.762)
			(end -1.524 -0.762)
			(stroke
				(width 0.1524)
				(type default)
			)
			(layer "B.SilkS")
		)
		(fp_line
			(start -1.524 -0.762)
			(end -1.524 0.762)
			(stroke
				(width 0.1524)
				(type default)
			)
			(layer "B.SilkS")
		)
		(fp_line
			(start 1.524 0.762)
			(end 1.524 -0.762)
			(stroke
				(width 0.1524)
				(type default)
			)
			(layer "B.SilkS")
		)
		(fp_line
			(start -1.524 0.762)
			(end 1.524 0.762)
			(stroke
				(width 0.1524)
				(type default)
			)
			(layer "B.SilkS")
		)
		(fp_line
			(start 1.1049 -0.724916)
			(end 1.1049 0.724916)
			(stroke
				(width 0.1)
				(type default)
			)
			(layer "B.Fab")
		)
		(fp_line
			(start -1.1049 -0.724916)
			(end 1.1049 -0.724916)
			(stroke
				(width 0.1)
				(type default)
			)
			(layer "B.Fab")
		)
		(fp_line
			(start 1.1049 0.724916)
			(end -1.1049 0.724916)
			(stroke
				(width 0.1)
				(type default)
			)
			(layer "B.Fab")
		)
		(fp_line
			(start -1.1049 0.724916)
			(end -1.1049 -0.724916)
			(stroke
				(width 0.1)
				(type default)
			)
			(layer "B.Fab")
		)
		(pad "1" smd rect
			(at 0.889 0 90)
			(size 1.016 1.27)
			(layers "B.Cu" "B.Mask" "B.Paste")
			(net "SW_P12V_AUX_PVDDCR_CPU1_P1_FLT")
		)
		(pad "2" smd rect
			(at -0.889 0 90)
			(size 1.016 1.27)
			(layers "B.Cu" "B.Mask" "B.Paste")
			(net "GND")
		)
	)
	(footprint ""
		(layer "B.Cu")
		(at 73.695814 -9.50468)
		(property "Reference" "R3175"
			(at 0 0 0)
			(layer "B.SilkS")
			(hide yes)
			(effects
				(font
					(size 1.27 1.27)
				)
				(justify mirror)
			)
		)
		(property "Value" ""
			(at 0 0 0)
			(layer "B.Fab")
			(effects
				(font
					(size 1.27 1.27)
				)
				(justify mirror)
			)
		)
		(duplicate_pad_numbers_are_jumpers no)
		(fp_line
			(start -0.7874 -0.4064)
			(end -0.7874 0.4064)
			(stroke
				(width 0.1524)
				(type default)
			)
			(layer "B.SilkS")
		)
		(fp_line
			(start -0.7874 0.4064)
			(end 0.7874 0.4064)
			(stroke
				(width 0.1524)
				(type default)
			)
			(layer "B.SilkS")
		)
		(fp_line
			(start 0.7874 -0.4064)
			(end -0.7874 -0.4064)
			(stroke
				(width 0.1524)
				(type default)
			)
			(layer "B.SilkS")
		)
		(fp_line
			(start 0.7874 0.4064)
			(end 0.7874 -0.4064)
			(stroke
				(width 0.1524)
				(type default)
			)
			(layer "B.SilkS")
		)
		(fp_line
			(start -0.67945 -0.3048)
			(end -0.67945 0.3048)
			(stroke
				(width 0.1)
				(type default)
			)
			(layer "B.Fab")
		)
		(fp_line
			(start -0.67945 0.3048)
			(end -0.120396 0.3048)
			(stroke
				(width 0.1)
				(type default)
			)
			(layer "B.Fab")
		)
		(fp_line
			(start -0.12065 -0.3048)
			(end -0.67945 -0.3048)
			(stroke
				(width 0.1)
				(type default)
			)
			(layer "B.Fab")
		)
		(fp_line
			(start -0.12065 -0.2794)
			(end -0.12065 -0.3048)
			(stroke
				(width 0.1)
				(type default)
			)
			(layer "B.Fab")
		)
		(fp_line
			(start -0.120396 0.2794)
			(end 0.12065 0.2794)
			(stroke
				(width 0.1)
				(type default)
			)
			(layer "B.Fab")
		)
		(fp_line
			(start -0.120396 0.3048)
			(end -0.120396 0.2794)
			(stroke
				(width 0.1)
				(type default)
			)
			(layer "B.Fab")
		)
		(fp_line
			(start 0.12065 -0.305054)
			(end 0.12065 -0.2794)
			(stroke
				(width 0.1)
				(type default)
			)
			(layer "B.Fab")
		)
		(fp_line
			(start 0.12065 -0.2794)
			(end -0.12065 -0.2794)
			(stroke
				(width 0.1)
				(type default)
			)
			(layer "B.Fab")
		)
		(fp_line
			(start 0.12065 0.2794)
			(end 0.12065 0.3048)
			(stroke
				(width 0.1)
				(type default)
			)
			(layer "B.Fab")
		)
		(fp_line
			(start 0.12065 0.3048)
			(end 0.67945 0.3048)
			(stroke
				(width 0.1)
				(type default)
			)
			(layer "B.Fab")
		)
		(fp_line
			(start 0.67945 -0.305054)
			(end 0.12065 -0.305054)
			(stroke
				(width 0.1)
				(type default)
			)
			(layer "B.Fab")
		)
		(fp_line
			(start 0.67945 0.3048)
			(end 0.67945 -0.305054)
			(stroke
				(width 0.1)
				(type default)
			)
			(layer "B.Fab")
		)
		(pad "1" smd circle
			(at 0.40005 0 180)
			(size 0 0)
			(layers "B.Cu" "B.Mask" "B.Paste")
			(net "SGPIO_OCP_V3_2_DATAOUT")
		)
		(pad "2" smd circle
			(at -0.40005 0 180)
			(size 0 0)
			(layers "B.Cu" "B.Mask" "B.Paste")
			(net "GND")
		)
	)
	(footprint ""
		(layer "B.Cu")
		(at 100.878386 -266.005564)
		(property "Reference" "C3922"
			(at 0 0 0)
			(layer "B.SilkS")
			(hide yes)
			(effects
				(font
					(size 1.27 1.27)
				)
				(justify mirror)
			)
		)
		(property "Value" ""
			(at 0 0 0)
			(layer "B.Fab")
			(effects
				(font
					(size 1.27 1.27)
				)
				(justify mirror)
			)
		)
		(duplicate_pad_numbers_are_jumpers no)
		(fp_line
			(start -0.7874 -0.4064)
			(end -0.7874 0.4064)
			(stroke
				(width 0.1524)
				(type default)
			)
			(layer "B.SilkS")
		)
		(fp_line
			(start -0.7874 0.4064)
			(end 0.7874 0.4064)
			(stroke
				(width 0.1524)
				(type default)
			)
			(layer "B.SilkS")
		)
		(fp_line
			(start 0.7874 -0.4064)
			(end -0.7874 -0.4064)
			(stroke
				(width 0.1524)
				(type default)
			)
			(layer "B.SilkS")
		)
		(fp_line
			(start 0.7874 0.4064)
			(end 0.7874 -0.4064)
			(stroke
				(width 0.1524)
				(type default)
			)
			(layer "B.SilkS")
		)
		(fp_line
			(start -0.67945 -0.3048)
			(end -0.67945 0.3048)
			(stroke
				(width 0.1)
				(type default)
			)
			(layer "B.Fab")
		)
		(fp_line
			(start -0.67945 0.3048)
			(end -0.120396 0.3048)
			(stroke
				(width 0.1)
				(type default)
			)
			(layer "B.Fab")
		)
		(fp_line
			(start -0.12065 -0.3048)
			(end -0.67945 -0.3048)
			(stroke
				(width 0.1)
				(type default)
			)
			(layer "B.Fab")
		)
		(fp_line
			(start -0.12065 -0.2794)
			(end -0.12065 -0.3048)
			(stroke
				(width 0.1)
				(type default)
			)
			(layer "B.Fab")
		)
		(fp_line
			(start -0.120396 0.2794)
			(end 0.12065 0.2794)
			(stroke
				(width 0.1)
				(type default)
			)
			(layer "B.Fab")
		)
		(fp_line
			(start -0.120396 0.3048)
			(end -0.120396 0.2794)
			(stroke
				(width 0.1)
				(type default)
			)
			(layer "B.Fab")
		)
		(fp_line
			(start 0.12065 -0.305054)
			(end 0.12065 -0.2794)
			(stroke
				(width 0.1)
				(type default)
			)
			(layer "B.Fab")
		)
		(fp_line
			(start 0.12065 -0.2794)
			(end -0.12065 -0.2794)
			(stroke
				(width 0.1)
				(type default)
			)
			(layer "B.Fab")
		)
		(fp_line
			(start 0.12065 0.2794)
			(end 0.12065 0.3048)
			(stroke
				(width 0.1)
				(type default)
			)
			(layer "B.Fab")
		)
		(fp_line
			(start 0.12065 0.3048)
			(end 0.67945 0.3048)
			(stroke
				(width 0.1)
				(type default)
			)
			(layer "B.Fab")
		)
		(fp_line
			(start 0.67945 -0.305054)
			(end 0.12065 -0.305054)
			(stroke
				(width 0.1)
				(type default)
			)
			(layer "B.Fab")
		)
		(fp_line
			(start 0.67945 0.3048)
			(end 0.67945 -0.305054)
			(stroke
				(width 0.1)
				(type default)
			)
			(layer "B.Fab")
		)
		(pad "1" smd circle
			(at 0.40005 0 180)
			(size 0 0)
			(layers "B.Cu" "B.Mask" "B.Paste")
			(net "PVDD11_S3_P1")
		)
		(pad "2" smd circle
			(at -0.40005 0 180)
			(size 0 0)
			(layers "B.Cu" "B.Mask" "B.Paste")
			(net "GND")
		)
	)
	(footprint ""
		(layer "B.Cu")
		(at 10.16 -81.153 -90)
		(property "Reference" "C8001"
			(at 0 0 90)
			(layer "B.SilkS")
			(hide yes)
			(effects
				(font
					(size 1.27 1.27)
				)
				(justify mirror)
			)
		)
		(property "Value" ""
			(at 0 0 90)
			(layer "B.Fab")
			(effects
				(font
					(size 1.27 1.27)
				)
				(justify mirror)
			)
		)
		(duplicate_pad_numbers_are_jumpers no)
		(fp_line
			(start -0.7874 0.4064)
			(end 0.7874 0.4064)
			(stroke
				(width 0.1524)
				(type default)
			)
			(layer "B.SilkS")
		)
		(fp_line
			(start 0.7874 0.4064)
			(end 0.7874 -0.4064)
			(stroke
				(width 0.1524)
				(type default)
			)
			(layer "B.SilkS")
		)
		(fp_line
			(start -0.7874 -0.4064)
			(end -0.7874 0.4064)
			(stroke
				(width 0.1524)
				(type default)
			)
			(layer "B.SilkS")
		)
		(fp_line
			(start 0.7874 -0.4064)
			(end -0.7874 -0.4064)
			(stroke
				(width 0.1524)
				(type default)
			)
			(layer "B.SilkS")
		)
		(fp_line
			(start -0.67945 0.3048)
			(end -0.120396 0.3048)
			(stroke
				(width 0.1)
				(type default)
			)
			(layer "B.Fab")
		)
		(fp_line
			(start -0.120396 0.3048)
			(end -0.120396 0.2794)
			(stroke
				(width 0.1)
				(type default)
			)
			(layer "B.Fab")
		)
		(fp_line
			(start 0.12065 0.3048)
			(end 0.67945 0.3048)
			(stroke
				(width 0.1)
				(type default)
			)
			(layer "B.Fab")
		)
		(fp_line
			(start 0.67945 0.3048)
			(end 0.67945 -0.305054)
			(stroke
				(width 0.1)
				(type default)
			)
			(layer "B.Fab")
		)
		(fp_line
			(start -0.120396 0.2794)
			(end 0.12065 0.2794)
			(stroke
				(width 0.1)
				(type default)
			)
			(layer "B.Fab")
		)
		(fp_line
			(start 0.12065 0.2794)
			(end 0.12065 0.3048)
			(stroke
				(width 0.1)
				(type default)
			)
			(layer "B.Fab")
		)
		(fp_line
			(start -0.12065 -0.2794)
			(end -0.12065 -0.3048)
			(stroke
				(width 0.1)
				(type default)
			)
			(layer "B.Fab")
		)
		(fp_line
			(start 0.12065 -0.2794)
			(end -0.12065 -0.2794)
			(stroke
				(width 0.1)
				(type default)
			)
			(layer "B.Fab")
		)
		(fp_line
			(start -0.67945 -0.3048)
			(end -0.67945 0.3048)
			(stroke
				(width 0.1)
				(type default)
			)
			(layer "B.Fab")
		)
		(fp_line
			(start -0.12065 -0.3048)
			(end -0.67945 -0.3048)
			(stroke
				(width 0.1)
				(type default)
			)
			(layer "B.Fab")
		)
		(fp_line
			(start 0.12065 -0.305054)
			(end 0.12065 -0.2794)
			(stroke
				(width 0.1)
				(type default)
			)
			(layer "B.Fab")
		)
		(fp_line
			(start 0.67945 -0.305054)
			(end 0.12065 -0.305054)
			(stroke
				(width 0.1)
				(type default)
			)
			(layer "B.Fab")
		)
		(pad "1" smd circle
			(at 0.40005 0 90)
			(size 0 0)
			(layers "B.Cu" "B.Mask" "B.Paste")
			(net "OCP_SFF_PRSNT01_R1_N")
		)
		(pad "2" smd circle
			(at -0.40005 0 90)
			(size 0 0)
			(layers "B.Cu" "B.Mask" "B.Paste")
			(net "GND")
		)
	)
	(footprint ""
		(layer "B.Cu")
		(at 190.163196 -244.085364)
		(property "Reference" "R509"
			(at 0 0 0)
			(layer "B.SilkS")
			(hide yes)
			(effects
				(font
					(size 1.27 1.27)
				)
				(justify mirror)
			)
		)
		(property "Value" ""
			(at 0 0 0)
			(layer "B.Fab")
			(effects
				(font
					(size 1.27 1.27)
				)
				(justify mirror)
			)
		)
		(duplicate_pad_numbers_are_jumpers no)
		(fp_line
			(start -0.7874 -0.4064)
			(end -0.7874 0.4064)
			(stroke
				(width 0.1524)
				(type default)
			)
			(layer "B.SilkS")
		)
		(fp_line
			(start -0.7874 0.4064)
			(end 0.7874 0.4064)
			(stroke
				(width 0.1524)
				(type default)
			)
			(layer "B.SilkS")
		)
		(fp_line
			(start 0.7874 -0.4064)
			(end -0.7874 -0.4064)
			(stroke
				(width 0.1524)
				(type default)
			)
			(layer "B.SilkS")
		)
		(fp_line
			(start 0.7874 0.4064)
			(end 0.7874 -0.4064)
			(stroke
				(width 0.1524)
				(type default)
			)
			(layer "B.SilkS")
		)
		(fp_line
			(start -0.67945 -0.3048)
			(end -0.67945 0.3048)
			(stroke
				(width 0.1)
				(type default)
			)
			(layer "B.Fab")
		)
		(fp_line
			(start -0.67945 0.3048)
			(end -0.120396 0.3048)
			(stroke
				(width 0.1)
				(type default)
			)
			(layer "B.Fab")
		)
		(fp_line
			(start -0.12065 -0.3048)
			(end -0.67945 -0.3048)
			(stroke
				(width 0.1)
				(type default)
			)
			(layer "B.Fab")
		)
		(fp_line
			(start -0.12065 -0.2794)
			(end -0.12065 -0.3048)
			(stroke
				(width 0.1)
				(type default)
			)
			(layer "B.Fab")
		)
		(fp_line
			(start -0.120396 0.2794)
			(end 0.12065 0.2794)
			(stroke
				(width 0.1)
				(type default)
			)
			(layer "B.Fab")
		)
		(fp_line
			(start -0.120396 0.3048)
			(end -0.120396 0.2794)
			(stroke
				(width 0.1)
				(type default)
			)
			(layer "B.Fab")
		)
		(fp_line
			(start 0.12065 -0.305054)
			(end 0.12065 -0.2794)
			(stroke
				(width 0.1)
				(type default)
			)
			(layer "B.Fab")
		)
		(fp_line
			(start 0.12065 -0.2794)
			(end -0.12065 -0.2794)
			(stroke
				(width 0.1)
				(type default)
			)
			(layer "B.Fab")
		)
		(fp_line
			(start 0.12065 0.2794)
			(end 0.12065 0.3048)
			(stroke
				(width 0.1)
				(type default)
			)
			(layer "B.Fab")
		)
		(fp_line
			(start 0.12065 0.3048)
			(end 0.67945 0.3048)
			(stroke
				(width 0.1)
				(type default)
			)
			(layer "B.Fab")
		)
		(fp_line
			(start 0.67945 -0.305054)
			(end 0.12065 -0.305054)
			(stroke
				(width 0.1)
				(type default)
			)
			(layer "B.Fab")
		)
		(fp_line
			(start 0.67945 0.3048)
			(end 0.67945 -0.305054)
			(stroke
				(width 0.1)
				(type default)
			)
			(layer "B.Fab")
		)
		(pad "1" smd circle
			(at 0.40005 0 180)
			(size 0 0)
			(layers "B.Cu" "B.Mask" "B.Paste")
			(net "M_J_CPU1_ALERT_N")
		)
		(pad "2" smd circle
			(at -0.40005 0 180)
			(size 0 0)
			(layers "B.Cu" "B.Mask" "B.Paste")
			(net "M_J_CPU1_ALERT_R_N")
		)
	)
	(footprint ""
		(layer "B.Cu")
		(at 197.269608 -126.833376 180)
		(property "Reference" "R265"
			(at 0 0 0)
			(layer "B.SilkS")
			(hide yes)
			(effects
				(font
					(size 1.27 1.27)
				)
				(justify mirror)
			)
		)
		(property "Value" ""
			(at 0 0 0)
			(layer "B.Fab")
			(effects
				(font
					(size 1.27 1.27)
				)
				(justify mirror)
			)
		)
		(duplicate_pad_numbers_are_jumpers no)
		(fp_line
			(start 0.7874 0.4064)
			(end 0.7874 -0.4064)
			(stroke
				(width 0.1524)
				(type default)
			)
			(layer "B.SilkS")
		)
		(fp_line
			(start 0.7874 -0.4064)
			(end -0.7874 -0.4064)
			(stroke
				(width 0.1524)
				(type default)
			)
			(layer "B.SilkS")
		)
		(fp_line
			(start -0.7874 0.4064)
			(end 0.7874 0.4064)
			(stroke
				(width 0.1524)
				(type default)
			)
			(layer "B.SilkS")
		)
		(fp_line
			(start -0.7874 -0.4064)
			(end -0.7874 0.4064)
			(stroke
				(width 0.1524)
				(type default)
			)
			(layer "B.SilkS")
		)
		(fp_line
			(start 0.67945 0.3048)
			(end 0.67945 -0.305054)
			(stroke
				(width 0.1)
				(type default)
			)
			(layer "B.Fab")
		)
		(fp_line
			(start 0.67945 -0.305054)
			(end 0.12065 -0.305054)
			(stroke
				(width 0.1)
				(type default)
			)
			(layer "B.Fab")
		)
		(fp_line
			(start 0.12065 0.3048)
			(end 0.67945 0.3048)
			(stroke
				(width 0.1)
				(type default)
			)
			(layer "B.Fab")
		)
		(fp_line
			(start 0.12065 0.2794)
			(end 0.12065 0.3048)
			(stroke
				(width 0.1)
				(type default)
			)
			(layer "B.Fab")
		)
		(fp_line
			(start 0.12065 -0.2794)
			(end -0.12065 -0.2794)
			(stroke
				(width 0.1)
				(type default)
			)
			(layer "B.Fab")
		)
		(fp_line
			(start 0.12065 -0.305054)
			(end 0.12065 -0.2794)
			(stroke
				(width 0.1)
				(type default)
			)
			(layer "B.Fab")
		)
		(fp_line
			(start -0.120396 0.3048)
			(end -0.120396 0.2794)
			(stroke
				(width 0.1)
				(type default)
			)
			(layer "B.Fab")
		)
		(fp_line
			(start -0.120396 0.2794)
			(end 0.12065 0.2794)
			(stroke
				(width 0.1)
				(type default)
			)
			(layer "B.Fab")
		)
		(fp_line
			(start -0.12065 -0.2794)
			(end -0.12065 -0.3048)
			(stroke
				(width 0.1)
				(type default)
			)
			(layer "B.Fab")
		)
		(fp_line
			(start -0.12065 -0.3048)
			(end -0.67945 -0.3048)
			(stroke
				(width 0.1)
				(type default)
			)
			(layer "B.Fab")
		)
		(fp_line
			(start -0.67945 0.3048)
			(end -0.120396 0.3048)
			(stroke
				(width 0.1)
				(type default)
			)
			(layer "B.Fab")
		)
		(fp_line
			(start -0.67945 -0.3048)
			(end -0.67945 0.3048)
			(stroke
				(width 0.1)
				(type default)
			)
			(layer "B.Fab")
		)
		(pad "1" smd circle
			(at 0.40005 0)
			(size 0 0)
			(layers "B.Cu" "B.Mask" "B.Paste")
			(net "FM_CPU1_FORCE_SELFREFRESH")
		)
		(pad "2" smd circle
			(at -0.40005 0)
			(size 0 0)
			(layers "B.Cu" "B.Mask" "B.Paste")
			(net "CPU1_FORCE_SELFREFRESH")
		)
	)
)
